(kicad_pcb
	(version 20260206)
	(generator "pcbnew")
	(generator_version "10.0")
	(general
		(thickness 1.6)
		(legacy_teardrops no)
	)
	(paper "A4")
	(title_block
		(title "04192023_DAF0TMB3IC0_F0TG_MB_C_brd_V02_OCP.brd")
		(comment 1 "Grand Teton / footprints 2232-2238 of 8354")
	)
	(layers
		(0 "F.Cu" signal "TOP")
		(4 "In1.Cu" signal "GND")
		(6 "In2.Cu" signal "IN1")
		(8 "In3.Cu" signal "GND1")
		(10 "In4.Cu" signal "IN2")
		(12 "In5.Cu" signal "GND2")
		(14 "In6.Cu" signal "IN3")
		(16 "In7.Cu" signal "GND3")
		(18 "In8.Cu" signal "VCC")
		(20 "In9.Cu" signal "VCC1")
		(22 "In10.Cu" signal "GND4")
		(24 "In11.Cu" signal "IN4")
		(26 "In12.Cu" signal "GND5")
		(28 "In13.Cu" signal "IN5")
		(30 "In14.Cu" signal "GND6")
		(32 "In15.Cu" signal "IN6")
		(34 "In16.Cu" signal "GND7")
		(2 "B.Cu" signal "BOTTOM")
		(9 "F.Adhes" user "F.Adhesive")
		(11 "B.Adhes" user "B.Adhesive")
		(13 "F.Paste" user "Package Geometry/Pastemask Top")
		(15 "B.Paste" user "Package Geometry/Pastemask Bottom")
		(5 "F.SilkS" user "Ref Des/Silkscreen Top")
		(7 "B.SilkS" user "Ref Des/Silkscreen Bottom")
		(1 "F.Mask" user "Board Geometry/Soldermask Top")
		(3 "B.Mask" user "Board Geometry/Soldermask Bottom")
		(17 "Dwgs.User" user "User.Drawings")
		(19 "Cmts.User" user "User.Comments")
		(21 "Eco1.User" user "User.Eco1")
		(23 "Eco2.User" user "User.Eco2")
		(25 "Edge.Cuts" user "Board Geometry/Outline")
		(27 "Margin" user)
		(31 "F.CrtYd" user "Package Geometry/Place Bound Top")
		(29 "B.CrtYd" user "Package Geometry/Place Bound Bottom")
		(35 "F.Fab" user "Ref Des/Assembly Top")
		(33 "B.Fab" user "Ref Des/Assembly Bottom")
	)
	(footprint ""
		(layer "F.Cu")
		(at 111.422942 -19.9898 -90)
		(property "Reference" "R6260"
			(at 0 0 270)
			(layer "F.SilkS")
			(hide yes)
			(effects
				(font
					(size 1.27 1.27)
				)
			)
		)
		(property "Value" ""
			(at 0 0 270)
			(layer "F.Fab")
			(effects
				(font
					(size 1.27 1.27)
				)
			)
		)
		(duplicate_pad_numbers_are_jumpers no)
		(fp_line
			(start -0.7874 0.4064)
			(end -0.7874 -0.4064)
			(stroke
				(width 0.1524)
				(type default)
			)
			(layer "F.SilkS")
		)
		(fp_line
			(start 0.7874 0.4064)
			(end -0.7874 0.4064)
			(stroke
				(width 0.1524)
				(type default)
			)
			(layer "F.SilkS")
		)
		(fp_line
			(start -0.7874 -0.4064)
			(end 0.7874 -0.4064)
			(stroke
				(width 0.1524)
				(type default)
			)
			(layer "F.SilkS")
		)
		(fp_line
			(start 0.7874 -0.4064)
			(end 0.7874 0.4064)
			(stroke
				(width 0.1524)
				(type default)
			)
			(layer "F.SilkS")
		)
		(fp_line
			(start -0.67945 0.3048)
			(end -0.67945 -0.305054)
			(stroke
				(width 0.1)
				(type default)
			)
			(layer "F.Fab")
		)
		(fp_line
			(start -0.12065 0.3048)
			(end -0.67945 0.3048)
			(stroke
				(width 0.1)
				(type default)
			)
			(layer "F.Fab")
		)
		(fp_line
			(start 0.120396 0.3048)
			(end 0.120396 0.2794)
			(stroke
				(width 0.1)
				(type default)
			)
			(layer "F.Fab")
		)
		(fp_line
			(start 0.67945 0.3048)
			(end 0.120396 0.3048)
			(stroke
				(width 0.1)
				(type default)
			)
			(layer "F.Fab")
		)
		(fp_line
			(start -0.12065 0.2794)
			(end -0.12065 0.3048)
			(stroke
				(width 0.1)
				(type default)
			)
			(layer "F.Fab")
		)
		(fp_line
			(start 0.120396 0.2794)
			(end -0.12065 0.2794)
			(stroke
				(width 0.1)
				(type default)
			)
			(layer "F.Fab")
		)
		(fp_line
			(start -0.12065 -0.2794)
			(end 0.12065 -0.2794)
			(stroke
				(width 0.1)
				(type default)
			)
			(layer "F.Fab")
		)
		(fp_line
			(start 0.12065 -0.2794)
			(end 0.12065 -0.3048)
			(stroke
				(width 0.1)
				(type default)
			)
			(layer "F.Fab")
		)
		(fp_line
			(start 0.12065 -0.3048)
			(end 0.67945 -0.3048)
			(stroke
				(width 0.1)
				(type default)
			)
			(layer "F.Fab")
		)
		(fp_line
			(start 0.67945 -0.3048)
			(end 0.67945 0.3048)
			(stroke
				(width 0.1)
				(type default)
			)
			(layer "F.Fab")
		)
		(fp_line
			(start -0.67945 -0.305054)
			(end -0.12065 -0.305054)
			(stroke
				(width 0.1)
				(type default)
			)
			(layer "F.Fab")
		)
		(fp_line
			(start -0.12065 -0.305054)
			(end -0.12065 -0.2794)
			(stroke
				(width 0.1)
				(type default)
			)
			(layer "F.Fab")
		)
		(pad "1" smd circle
			(at -0.40005 0 270)
			(size 0 0)
			(layers "F.Cu" "F.Mask" "F.Paste")
			(net "USB_HUB2_TI_VDD_MRP_USB3DN_TXDM1")
		)
		(pad "2" smd circle
			(at 0.40005 0 270)
			(size 0 0)
			(layers "F.Cu" "F.Mask" "F.Paste")
			(net "P1V2_CPU0_USB2_DVDD12")
		)
	)
	(footprint ""
		(layer "F.Cu")
		(at 178.044602 -32.950912 90)
		(property "Reference" "PR3999"
			(at 0 0 90)
			(layer "F.SilkS")
			(hide yes)
			(effects
				(font
					(size 1.27 1.27)
				)
			)
		)
		(property "Value" ""
			(at 0 0 90)
			(layer "F.Fab")
			(effects
				(font
					(size 1.27 1.27)
				)
			)
		)
		(duplicate_pad_numbers_are_jumpers no)
		(fp_line
			(start 0.7874 -0.4064)
			(end 0.7874 0.4064)
			(stroke
				(width 0.1524)
				(type default)
			)
			(layer "F.SilkS")
		)
		(fp_line
			(start -0.7874 -0.4064)
			(end 0.7874 -0.4064)
			(stroke
				(width 0.1524)
				(type default)
			)
			(layer "F.SilkS")
		)
		(fp_line
			(start 0.7874 0.4064)
			(end -0.7874 0.4064)
			(stroke
				(width 0.1524)
				(type default)
			)
			(layer "F.SilkS")
		)
		(fp_line
			(start -0.7874 0.4064)
			(end -0.7874 -0.4064)
			(stroke
				(width 0.1524)
				(type default)
			)
			(layer "F.SilkS")
		)
		(fp_line
			(start -0.12065 -0.305054)
			(end -0.12065 -0.2794)
			(stroke
				(width 0.1)
				(type default)
			)
			(layer "F.Fab")
		)
		(fp_line
			(start -0.67945 -0.305054)
			(end -0.12065 -0.305054)
			(stroke
				(width 0.1)
				(type default)
			)
			(layer "F.Fab")
		)
		(fp_line
			(start 0.67945 -0.3048)
			(end 0.67945 0.3048)
			(stroke
				(width 0.1)
				(type default)
			)
			(layer "F.Fab")
		)
		(fp_line
			(start 0.12065 -0.3048)
			(end 0.67945 -0.3048)
			(stroke
				(width 0.1)
				(type default)
			)
			(layer "F.Fab")
		)
		(fp_line
			(start 0.12065 -0.2794)
			(end 0.12065 -0.3048)
			(stroke
				(width 0.1)
				(type default)
			)
			(layer "F.Fab")
		)
		(fp_line
			(start -0.12065 -0.2794)
			(end 0.12065 -0.2794)
			(stroke
				(width 0.1)
				(type default)
			)
			(layer "F.Fab")
		)
		(fp_line
			(start 0.120396 0.2794)
			(end -0.12065 0.2794)
			(stroke
				(width 0.1)
				(type default)
			)
			(layer "F.Fab")
		)
		(fp_line
			(start -0.12065 0.2794)
			(end -0.12065 0.3048)
			(stroke
				(width 0.1)
				(type default)
			)
			(layer "F.Fab")
		)
		(fp_line
			(start 0.67945 0.3048)
			(end 0.120396 0.3048)
			(stroke
				(width 0.1)
				(type default)
			)
			(layer "F.Fab")
		)
		(fp_line
			(start 0.120396 0.3048)
			(end 0.120396 0.2794)
			(stroke
				(width 0.1)
				(type default)
			)
			(layer "F.Fab")
		)
		(fp_line
			(start -0.12065 0.3048)
			(end -0.67945 0.3048)
			(stroke
				(width 0.1)
				(type default)
			)
			(layer "F.Fab")
		)
		(fp_line
			(start -0.67945 0.3048)
			(end -0.67945 -0.305054)
			(stroke
				(width 0.1)
				(type default)
			)
			(layer "F.Fab")
		)
		(pad "1" smd circle
			(at -0.40005 0 90)
			(size 0 0)
			(layers "F.Cu" "F.Mask" "F.Paste")
			(net "P12V_SCM_ISET")
		)
		(pad "2" smd circle
			(at 0.40005 0 90)
			(size 0 0)
			(layers "F.Cu" "F.Mask" "F.Paste")
			(net "GND")
		)
	)
	(footprint ""
		(layer "F.Cu")
		(at 22.479 -366.903)
		(property "Reference" "R1321"
			(at 0 0 0)
			(layer "F.SilkS")
			(hide yes)
			(effects
				(font
					(size 1.27 1.27)
				)
			)
		)
		(property "Value" ""
			(at 0 0 0)
			(layer "F.Fab")
			(effects
				(font
					(size 1.27 1.27)
				)
			)
		)
		(duplicate_pad_numbers_are_jumpers no)
		(fp_line
			(start -0.7874 -0.4064)
			(end 0.7874 -0.4064)
			(stroke
				(width 0.1524)
				(type default)
			)
			(layer "F.SilkS")
		)
		(fp_line
			(start -0.7874 0.4064)
			(end -0.7874 -0.4064)
			(stroke
				(width 0.1524)
				(type default)
			)
			(layer "F.SilkS")
		)
		(fp_line
			(start 0.7874 -0.4064)
			(end 0.7874 0.4064)
			(stroke
				(width 0.1524)
				(type default)
			)
			(layer "F.SilkS")
		)
		(fp_line
			(start 0.7874 0.4064)
			(end -0.7874 0.4064)
			(stroke
				(width 0.1524)
				(type default)
			)
			(layer "F.SilkS")
		)
		(fp_line
			(start -0.67945 -0.305054)
			(end -0.12065 -0.305054)
			(stroke
				(width 0.1)
				(type default)
			)
			(layer "F.Fab")
		)
		(fp_line
			(start -0.67945 0.3048)
			(end -0.67945 -0.305054)
			(stroke
				(width 0.1)
				(type default)
			)
			(layer "F.Fab")
		)
		(fp_line
			(start -0.12065 -0.305054)
			(end -0.12065 -0.2794)
			(stroke
				(width 0.1)
				(type default)
			)
			(layer "F.Fab")
		)
		(fp_line
			(start -0.12065 -0.2794)
			(end 0.12065 -0.2794)
			(stroke
				(width 0.1)
				(type default)
			)
			(layer "F.Fab")
		)
		(fp_line
			(start -0.12065 0.2794)
			(end -0.12065 0.3048)
			(stroke
				(width 0.1)
				(type default)
			)
			(layer "F.Fab")
		)
		(fp_line
			(start -0.12065 0.3048)
			(end -0.67945 0.3048)
			(stroke
				(width 0.1)
				(type default)
			)
			(layer "F.Fab")
		)
		(fp_line
			(start 0.120396 0.2794)
			(end -0.12065 0.2794)
			(stroke
				(width 0.1)
				(type default)
			)
			(layer "F.Fab")
		)
		(fp_line
			(start 0.120396 0.3048)
			(end 0.120396 0.2794)
			(stroke
				(width 0.1)
				(type default)
			)
			(layer "F.Fab")
		)
		(fp_line
			(start 0.12065 -0.3048)
			(end 0.67945 -0.3048)
			(stroke
				(width 0.1)
				(type default)
			)
			(layer "F.Fab")
		)
		(fp_line
			(start 0.12065 -0.2794)
			(end 0.12065 -0.3048)
			(stroke
				(width 0.1)
				(type default)
			)
			(layer "F.Fab")
		)
		(fp_line
			(start 0.67945 -0.3048)
			(end 0.67945 0.3048)
			(stroke
				(width 0.1)
				(type default)
			)
			(layer "F.Fab")
		)
		(fp_line
			(start 0.67945 0.3048)
			(end 0.120396 0.3048)
			(stroke
				(width 0.1)
				(type default)
			)
			(layer "F.Fab")
		)
		(pad "1" smd circle
			(at -0.40005 0)
			(size 0 0)
			(layers "F.Cu" "F.Mask" "F.Paste")
			(net "SMB_VR_3V3STBY_SCL")
		)
		(pad "2" smd circle
			(at 0.40005 0)
			(size 0 0)
			(layers "F.Cu" "F.Mask" "F.Paste")
			(net "SMB_SCM_2_R1_SCL")
		)
	)
	(footprint ""
		(layer "F.Cu")
		(at 105.222548 -386.7912 90)
		(property "Reference" "R746"
			(at 0 0 90)
			(layer "F.SilkS")
			(hide yes)
			(effects
				(font
					(size 1.27 1.27)
				)
			)
		)
		(property "Value" ""
			(at 0 0 90)
			(layer "F.Fab")
			(effects
				(font
					(size 1.27 1.27)
				)
			)
		)
		(duplicate_pad_numbers_are_jumpers no)
		(fp_line
			(start 0.32512 -0.175006)
			(end 0.32512 0.175006)
			(stroke
				(width 0.1)
				(type default)
			)
			(layer "F.Fab")
		)
		(fp_line
			(start -0.32512 -0.175006)
			(end 0.32512 -0.175006)
			(stroke
				(width 0.1)
				(type default)
			)
			(layer "F.Fab")
		)
		(fp_line
			(start 0.32512 0.175006)
			(end -0.32512 0.175006)
			(stroke
				(width 0.1)
				(type default)
			)
			(layer "F.Fab")
		)
		(fp_line
			(start -0.32512 0.175006)
			(end -0.32512 -0.175006)
			(stroke
				(width 0.1)
				(type default)
			)
			(layer "F.Fab")
		)
		(pad "1" smd rect
			(at -0.2667 0 90)
			(size 0.3048 0.381)
			(layers "F.Cu" "F.Mask" "F.Paste")
			(net "RT_CPU1_P1_ADDR2")
		)
		(pad "2" smd rect
			(at 0.2667 0 270)
			(size 0.3048 0.381)
			(layers "F.Cu" "F.Mask" "F.Paste")
			(net "GND")
		)
	)
	(footprint ""
		(layer "F.Cu")
		(at 42.33926 -379.56236)
		(property "Reference" "R675"
			(at 0 0 0)
			(layer "F.SilkS")
			(hide yes)
			(effects
				(font
					(size 1.27 1.27)
				)
			)
		)
		(property "Value" ""
			(at 0 0 0)
			(layer "F.Fab")
			(effects
				(font
					(size 1.27 1.27)
				)
			)
		)
		(duplicate_pad_numbers_are_jumpers no)
		(fp_line
			(start -0.32512 -0.175006)
			(end 0.32512 -0.175006)
			(stroke
				(width 0.1)
				(type default)
			)
			(layer "F.Fab")
		)
		(fp_line
			(start -0.32512 0.175006)
			(end -0.32512 -0.175006)
			(stroke
				(width 0.1)
				(type default)
			)
			(layer "F.Fab")
		)
		(fp_line
			(start 0.32512 -0.175006)
			(end 0.32512 0.175006)
			(stroke
				(width 0.1)
				(type default)
			)
			(layer "F.Fab")
		)
		(fp_line
			(start 0.32512 0.175006)
			(end -0.32512 0.175006)
			(stroke
				(width 0.1)
				(type default)
			)
			(layer "F.Fab")
		)
		(pad "1" smd rect
			(at -0.2667 0)
			(size 0.3048 0.381)
			(layers "F.Cu" "F.Mask" "F.Paste")
			(net "SMB_RT_CPU1_P0_ROM_MUX_1D_SDA")
		)
		(pad "2" smd rect
			(at 0.2667 0 180)
			(size 0.3048 0.381)
			(layers "F.Cu" "F.Mask" "F.Paste")
			(net "SMB_RT_CPU1_P0_ROM_MUX_1D_R_SDA")
		)
	)
	(footprint ""
		(layer "F.Cu")
		(at 438.056782 -439.12536 90)
		(property "Reference" "R4161"
			(at 0 0 90)
			(layer "F.SilkS")
			(hide yes)
			(effects
				(font
					(size 1.27 1.27)
				)
			)
		)
		(property "Value" ""
			(at 0 0 90)
			(layer "F.Fab")
			(effects
				(font
					(size 1.27 1.27)
				)
			)
		)
		(duplicate_pad_numbers_are_jumpers no)
		(fp_line
			(start 0.7874 -0.4064)
			(end 0.7874 0.4064)
			(stroke
				(width 0.1524)
				(type default)
			)
			(layer "F.SilkS")
		)
		(fp_line
			(start -0.7874 -0.4064)
			(end 0.7874 -0.4064)
			(stroke
				(width 0.1524)
				(type default)
			)
			(layer "F.SilkS")
		)
		(fp_line
			(start 0.7874 0.4064)
			(end -0.7874 0.4064)
			(stroke
				(width 0.1524)
				(type default)
			)
			(layer "F.SilkS")
		)
		(fp_line
			(start -0.7874 0.4064)
			(end -0.7874 -0.4064)
			(stroke
				(width 0.1524)
				(type default)
			)
			(layer "F.SilkS")
		)
		(fp_line
			(start -0.12065 -0.305054)
			(end -0.12065 -0.2794)
			(stroke
				(width 0.1)
				(type default)
			)
			(layer "F.Fab")
		)
		(fp_line
			(start -0.67945 -0.305054)
			(end -0.12065 -0.305054)
			(stroke
				(width 0.1)
				(type default)
			)
			(layer "F.Fab")
		)
		(fp_line
			(start 0.67945 -0.3048)
			(end 0.67945 0.3048)
			(stroke
				(width 0.1)
				(type default)
			)
			(layer "F.Fab")
		)
		(fp_line
			(start 0.12065 -0.3048)
			(end 0.67945 -0.3048)
			(stroke
				(width 0.1)
				(type default)
			)
			(layer "F.Fab")
		)
		(fp_line
			(start 0.12065 -0.2794)
			(end 0.12065 -0.3048)
			(stroke
				(width 0.1)
				(type default)
			)
			(layer "F.Fab")
		)
		(fp_line
			(start -0.12065 -0.2794)
			(end 0.12065 -0.2794)
			(stroke
				(width 0.1)
				(type default)
			)
			(layer "F.Fab")
		)
		(fp_line
			(start 0.120396 0.2794)
			(end -0.12065 0.2794)
			(stroke
				(width 0.1)
				(type default)
			)
			(layer "F.Fab")
		)
		(fp_line
			(start -0.12065 0.2794)
			(end -0.12065 0.3048)
			(stroke
				(width 0.1)
				(type default)
			)
			(layer "F.Fab")
		)
		(fp_line
			(start 0.67945 0.3048)
			(end 0.120396 0.3048)
			(stroke
				(width 0.1)
				(type default)
			)
			(layer "F.Fab")
		)
		(fp_line
			(start 0.120396 0.3048)
			(end 0.120396 0.2794)
			(stroke
				(width 0.1)
				(type default)
			)
			(layer "F.Fab")
		)
		(fp_line
			(start -0.12065 0.3048)
			(end -0.67945 0.3048)
			(stroke
				(width 0.1)
				(type default)
			)
			(layer "F.Fab")
		)
		(fp_line
			(start -0.67945 0.3048)
			(end -0.67945 -0.305054)
			(stroke
				(width 0.1)
				(type default)
			)
			(layer "F.Fab")
		)
		(pad "1" smd circle
			(at -0.40005 0 90)
			(size 0 0)
			(layers "F.Cu" "F.Mask" "F.Paste")
			(net "GPU_3V3IO_RSVD4")
		)
		(pad "2" smd circle
			(at 0.40005 0 90)
			(size 0 0)
			(layers "F.Cu" "F.Mask" "F.Paste")
			(net "GND")
		)
	)
	(footprint ""
		(layer "F.Cu")
		(at 111.76 -407.4668)
		(property "Reference" "R6803"
			(at 0 0 0)
			(layer "F.SilkS")
			(hide yes)
			(effects
				(font
					(size 1.27 1.27)
				)
			)
		)
		(property "Value" ""
			(at 0 0 0)
			(layer "F.Fab")
			(effects
				(font
					(size 1.27 1.27)
				)
			)
		)
		(duplicate_pad_numbers_are_jumpers no)
		(fp_line
			(start -0.7874 -0.4064)
			(end 0.7874 -0.4064)
			(stroke
				(width 0.1524)
				(type default)
			)
			(layer "F.SilkS")
		)
		(fp_line
			(start -0.7874 0.4064)
			(end -0.7874 -0.4064)
			(stroke
				(width 0.1524)
				(type default)
			)
			(layer "F.SilkS")
		)
		(fp_line
			(start 0.7874 -0.4064)
			(end 0.7874 0.4064)
			(stroke
				(width 0.1524)
				(type default)
			)
			(layer "F.SilkS")
		)
		(fp_line
			(start 0.7874 0.4064)
			(end -0.7874 0.4064)
			(stroke
				(width 0.1524)
				(type default)
			)
			(layer "F.SilkS")
		)
		(fp_line
			(start -0.67945 -0.305054)
			(end -0.12065 -0.305054)
			(stroke
				(width 0.1)
				(type default)
			)
			(layer "F.Fab")
		)
		(fp_line
			(start -0.67945 0.3048)
			(end -0.67945 -0.305054)
			(stroke
				(width 0.1)
				(type default)
			)
			(layer "F.Fab")
		)
		(fp_line
			(start -0.12065 -0.305054)
			(end -0.12065 -0.2794)
			(stroke
				(width 0.1)
				(type default)
			)
			(layer "F.Fab")
		)
		(fp_line
			(start -0.12065 -0.2794)
			(end 0.12065 -0.2794)
			(stroke
				(width 0.1)
				(type default)
			)
			(layer "F.Fab")
		)
		(fp_line
			(start -0.12065 0.2794)
			(end -0.12065 0.3048)
			(stroke
				(width 0.1)
				(type default)
			)
			(layer "F.Fab")
		)
		(fp_line
			(start -0.12065 0.3048)
			(end -0.67945 0.3048)
			(stroke
				(width 0.1)
				(type default)
			)
			(layer "F.Fab")
		)
		(fp_line
			(start 0.120396 0.2794)
			(end -0.12065 0.2794)
			(stroke
				(width 0.1)
				(type default)
			)
			(layer "F.Fab")
		)
		(fp_line
			(start 0.120396 0.3048)
			(end 0.120396 0.2794)
			(stroke
				(width 0.1)
				(type default)
			)
			(layer "F.Fab")
		)
		(fp_line
			(start 0.12065 -0.3048)
			(end 0.67945 -0.3048)
			(stroke
				(width 0.1)
				(type default)
			)
			(layer "F.Fab")
		)
		(fp_line
			(start 0.12065 -0.2794)
			(end 0.12065 -0.3048)
			(stroke
				(width 0.1)
				(type default)
			)
			(layer "F.Fab")
		)
		(fp_line
			(start 0.67945 -0.3048)
			(end 0.67945 0.3048)
			(stroke
				(width 0.1)
				(type default)
			)
			(layer "F.Fab")
		)
		(fp_line
			(start 0.67945 0.3048)
			(end 0.120396 0.3048)
			(stroke
				(width 0.1)
				(type default)
			)
			(layer "F.Fab")
		)
		(pad "1" smd circle
			(at -0.40005 0)
			(size 0 0)
			(layers "F.Cu" "F.Mask" "F.Paste")
			(net "FM_9ZXL045_P1_3_OE_N")
		)
		(pad "2" smd circle
			(at 0.40005 0)
			(size 0 0)
			(layers "F.Cu" "F.Mask" "F.Paste")
			(net "GND")
		)
	)
)
